(kicad_pcb
	(version 20260206)
	(generator "pcbnew")
	(generator_version "10.0")
	(general
		(thickness 1.6)
		(legacy_teardrops no)
	)
	(paper "A4")
	(title_block
		(title "01162023_DA0F0TEBIF0_F0T_Expander_BD_F_brd_V02_OCP.brd")
		(comment 1 "Grand Teton / footprints 6916-6922 of 9728")
	)
	(layers
		(0 "F.Cu" signal "TOP")
		(4 "In1.Cu" signal "GND")
		(6 "In2.Cu" signal "VCC")
		(8 "In3.Cu" signal "VCC1")
		(10 "In4.Cu" signal "GND1")
		(12 "In5.Cu" signal "IN1")
		(14 "In6.Cu" signal "GND2")
		(16 "In7.Cu" signal "IN2")
		(18 "In8.Cu" signal "GND3")
		(20 "In9.Cu" signal "IN3")
		(22 "In10.Cu" signal "GND4")
		(24 "In11.Cu" signal "IN4")
		(26 "In12.Cu" signal "GND5")
		(28 "In13.Cu" signal "IN5")
		(30 "In14.Cu" signal "GND6")
		(32 "In15.Cu" signal "IN6")
		(34 "In16.Cu" signal "GND7")
		(2 "B.Cu" signal "BOTTOM")
		(9 "F.Adhes" user "F.Adhesive")
		(11 "B.Adhes" user "B.Adhesive")
		(13 "F.Paste" user "Package Geometry/Pastemask Top")
		(15 "B.Paste" user "Package Geometry/Pastemask Bottom")
		(5 "F.SilkS" user "Ref Des/Silkscreen Top")
		(7 "B.SilkS" user "Ref Des/Silkscreen Bottom")
		(1 "F.Mask" user "Board Geometry/Soldermask Top")
		(3 "B.Mask" user "Board Geometry/Soldermask Bottom")
		(17 "Dwgs.User" user "User.Drawings")
		(19 "Cmts.User" user "User.Comments")
		(21 "Eco1.User" user "User.Eco1")
		(23 "Eco2.User" user "User.Eco2")
		(25 "Edge.Cuts" user "Board Geometry/Outline")
		(27 "Margin" user)
		(31 "F.CrtYd" user "Package Geometry/Place Bound Top")
		(29 "B.CrtYd" user "Package Geometry/Place Bound Bottom")
		(35 "F.Fab" user "Ref Des/Assembly Top")
		(33 "B.Fab" user "Ref Des/Assembly Bottom")
	)
	(footprint ""
		(layer "F.Cu")
		(at 230.4542 -231.4194 -90)
		(property "Reference" "R4537"
			(at 0 0 270)
			(layer "F.SilkS")
			(hide yes)
			(effects
				(font
					(size 1.27 1.27)
				)
			)
		)
		(property "Value" ""
			(at 0 0 270)
			(layer "F.Fab")
			(effects
				(font
					(size 1.27 1.27)
				)
			)
		)
		(duplicate_pad_numbers_are_jumpers no)
		(fp_line
			(start -0.7874 0.4064)
			(end -0.7874 -0.4064)
			(stroke
				(width 0.1524)
				(type default)
			)
			(layer "F.SilkS")
		)
		(fp_line
			(start 0.7874 0.4064)
			(end -0.7874 0.4064)
			(stroke
				(width 0.1524)
				(type default)
			)
			(layer "F.SilkS")
		)
		(fp_line
			(start -0.7874 -0.4064)
			(end 0.7874 -0.4064)
			(stroke
				(width 0.1524)
				(type default)
			)
			(layer "F.SilkS")
		)
		(fp_line
			(start 0.7874 -0.4064)
			(end 0.7874 0.4064)
			(stroke
				(width 0.1524)
				(type default)
			)
			(layer "F.SilkS")
		)
		(fp_line
			(start -0.67945 0.3048)
			(end -0.67945 -0.305054)
			(stroke
				(width 0.1)
				(type default)
			)
			(layer "F.Fab")
		)
		(fp_line
			(start -0.12065 0.3048)
			(end -0.67945 0.3048)
			(stroke
				(width 0.1)
				(type default)
			)
			(layer "F.Fab")
		)
		(fp_line
			(start 0.120396 0.3048)
			(end 0.120396 0.2794)
			(stroke
				(width 0.1)
				(type default)
			)
			(layer "F.Fab")
		)
		(fp_line
			(start 0.67945 0.3048)
			(end 0.120396 0.3048)
			(stroke
				(width 0.1)
				(type default)
			)
			(layer "F.Fab")
		)
		(fp_line
			(start -0.12065 0.2794)
			(end -0.12065 0.3048)
			(stroke
				(width 0.1)
				(type default)
			)
			(layer "F.Fab")
		)
		(fp_line
			(start 0.120396 0.2794)
			(end -0.12065 0.2794)
			(stroke
				(width 0.1)
				(type default)
			)
			(layer "F.Fab")
		)
		(fp_line
			(start -0.12065 -0.2794)
			(end 0.12065 -0.2794)
			(stroke
				(width 0.1)
				(type default)
			)
			(layer "F.Fab")
		)
		(fp_line
			(start 0.12065 -0.2794)
			(end 0.12065 -0.3048)
			(stroke
				(width 0.1)
				(type default)
			)
			(layer "F.Fab")
		)
		(fp_line
			(start 0.12065 -0.3048)
			(end 0.67945 -0.3048)
			(stroke
				(width 0.1)
				(type default)
			)
			(layer "F.Fab")
		)
		(fp_line
			(start 0.67945 -0.3048)
			(end 0.67945 0.3048)
			(stroke
				(width 0.1)
				(type default)
			)
			(layer "F.Fab")
		)
		(fp_line
			(start -0.67945 -0.305054)
			(end -0.12065 -0.305054)
			(stroke
				(width 0.1)
				(type default)
			)
			(layer "F.Fab")
		)
		(fp_line
			(start -0.12065 -0.305054)
			(end -0.12065 -0.2794)
			(stroke
				(width 0.1)
				(type default)
			)
			(layer "F.Fab")
		)
		(pad "1" smd circle
			(at -0.40005 0 270)
			(size 0 0)
			(layers "F.Cu" "F.Mask" "F.Paste")
			(net "NIC1_MAIN_PWR_BIC_EN_R")
		)
		(pad "2" smd circle
			(at 0.40005 0 270)
			(size 0 0)
			(layers "F.Cu" "F.Mask" "F.Paste")
			(net "NIC1_MAIN_PWR_BIC_EN")
		)
	)
	(footprint ""
		(layer "F.Cu")
		(at 149.586442 -250.070874 -90)
		(property "Reference" "R1266"
			(at 0 0 270)
			(layer "F.SilkS")
			(hide yes)
			(effects
				(font
					(size 1.27 1.27)
				)
			)
		)
		(property "Value" ""
			(at 0 0 270)
			(layer "F.Fab")
			(effects
				(font
					(size 1.27 1.27)
				)
			)
		)
		(duplicate_pad_numbers_are_jumpers no)
		(fp_line
			(start -0.7874 0.4064)
			(end -0.7874 -0.4064)
			(stroke
				(width 0.1524)
				(type default)
			)
			(layer "F.SilkS")
		)
		(fp_line
			(start 0.7874 0.4064)
			(end -0.7874 0.4064)
			(stroke
				(width 0.1524)
				(type default)
			)
			(layer "F.SilkS")
		)
		(fp_line
			(start -0.7874 -0.4064)
			(end 0.7874 -0.4064)
			(stroke
				(width 0.1524)
				(type default)
			)
			(layer "F.SilkS")
		)
		(fp_line
			(start 0.7874 -0.4064)
			(end 0.7874 0.4064)
			(stroke
				(width 0.1524)
				(type default)
			)
			(layer "F.SilkS")
		)
		(fp_line
			(start -0.67945 0.3048)
			(end -0.67945 -0.305054)
			(stroke
				(width 0.1)
				(type default)
			)
			(layer "F.Fab")
		)
		(fp_line
			(start -0.12065 0.3048)
			(end -0.67945 0.3048)
			(stroke
				(width 0.1)
				(type default)
			)
			(layer "F.Fab")
		)
		(fp_line
			(start 0.120396 0.3048)
			(end 0.120396 0.2794)
			(stroke
				(width 0.1)
				(type default)
			)
			(layer "F.Fab")
		)
		(fp_line
			(start 0.67945 0.3048)
			(end 0.120396 0.3048)
			(stroke
				(width 0.1)
				(type default)
			)
			(layer "F.Fab")
		)
		(fp_line
			(start -0.12065 0.2794)
			(end -0.12065 0.3048)
			(stroke
				(width 0.1)
				(type default)
			)
			(layer "F.Fab")
		)
		(fp_line
			(start 0.120396 0.2794)
			(end -0.12065 0.2794)
			(stroke
				(width 0.1)
				(type default)
			)
			(layer "F.Fab")
		)
		(fp_line
			(start -0.12065 -0.2794)
			(end 0.12065 -0.2794)
			(stroke
				(width 0.1)
				(type default)
			)
			(layer "F.Fab")
		)
		(fp_line
			(start 0.12065 -0.2794)
			(end 0.12065 -0.3048)
			(stroke
				(width 0.1)
				(type default)
			)
			(layer "F.Fab")
		)
		(fp_line
			(start 0.12065 -0.3048)
			(end 0.67945 -0.3048)
			(stroke
				(width 0.1)
				(type default)
			)
			(layer "F.Fab")
		)
		(fp_line
			(start 0.67945 -0.3048)
			(end 0.67945 0.3048)
			(stroke
				(width 0.1)
				(type default)
			)
			(layer "F.Fab")
		)
		(fp_line
			(start -0.67945 -0.305054)
			(end -0.12065 -0.305054)
			(stroke
				(width 0.1)
				(type default)
			)
			(layer "F.Fab")
		)
		(fp_line
			(start -0.12065 -0.305054)
			(end -0.12065 -0.2794)
			(stroke
				(width 0.1)
				(type default)
			)
			(layer "F.Fab")
		)
		(pad "1" smd circle
			(at -0.40005 0 270)
			(size 0 0)
			(layers "F.Cu" "F.Mask" "F.Paste")
			(net "PEX1_DBG_MODE2")
		)
		(pad "2" smd circle
			(at 0.40005 0 270)
			(size 0 0)
			(layers "F.Cu" "F.Mask" "F.Paste")
			(net "P1V8_PEX")
		)
	)
	(footprint ""
		(layer "F.Cu")
		(at 235.557822 -27.006296 -90)
		(property "Reference" "PR7115"
			(at 0 0 270)
			(layer "F.SilkS")
			(hide yes)
			(effects
				(font
					(size 1.27 1.27)
				)
			)
		)
		(property "Value" ""
			(at 0 0 270)
			(layer "F.Fab")
			(effects
				(font
					(size 1.27 1.27)
				)
			)
		)
		(duplicate_pad_numbers_are_jumpers no)
		(fp_line
			(start -0.7874 0.4064)
			(end -0.7874 -0.4064)
			(stroke
				(width 0.1524)
				(type default)
			)
			(layer "F.SilkS")
		)
		(fp_line
			(start 0.7874 0.4064)
			(end -0.7874 0.4064)
			(stroke
				(width 0.1524)
				(type default)
			)
			(layer "F.SilkS")
		)
		(fp_line
			(start -0.7874 -0.4064)
			(end 0.7874 -0.4064)
			(stroke
				(width 0.1524)
				(type default)
			)
			(layer "F.SilkS")
		)
		(fp_line
			(start 0.7874 -0.4064)
			(end 0.7874 0.4064)
			(stroke
				(width 0.1524)
				(type default)
			)
			(layer "F.SilkS")
		)
		(fp_line
			(start -0.67945 0.3048)
			(end -0.67945 -0.305054)
			(stroke
				(width 0.1)
				(type default)
			)
			(layer "F.Fab")
		)
		(fp_line
			(start -0.12065 0.3048)
			(end -0.67945 0.3048)
			(stroke
				(width 0.1)
				(type default)
			)
			(layer "F.Fab")
		)
		(fp_line
			(start 0.120396 0.3048)
			(end 0.120396 0.2794)
			(stroke
				(width 0.1)
				(type default)
			)
			(layer "F.Fab")
		)
		(fp_line
			(start 0.67945 0.3048)
			(end 0.120396 0.3048)
			(stroke
				(width 0.1)
				(type default)
			)
			(layer "F.Fab")
		)
		(fp_line
			(start -0.12065 0.2794)
			(end -0.12065 0.3048)
			(stroke
				(width 0.1)
				(type default)
			)
			(layer "F.Fab")
		)
		(fp_line
			(start 0.120396 0.2794)
			(end -0.12065 0.2794)
			(stroke
				(width 0.1)
				(type default)
			)
			(layer "F.Fab")
		)
		(fp_line
			(start -0.12065 -0.2794)
			(end 0.12065 -0.2794)
			(stroke
				(width 0.1)
				(type default)
			)
			(layer "F.Fab")
		)
		(fp_line
			(start 0.12065 -0.2794)
			(end 0.12065 -0.3048)
			(stroke
				(width 0.1)
				(type default)
			)
			(layer "F.Fab")
		)
		(fp_line
			(start 0.12065 -0.3048)
			(end 0.67945 -0.3048)
			(stroke
				(width 0.1)
				(type default)
			)
			(layer "F.Fab")
		)
		(fp_line
			(start 0.67945 -0.3048)
			(end 0.67945 0.3048)
			(stroke
				(width 0.1)
				(type default)
			)
			(layer "F.Fab")
		)
		(fp_line
			(start -0.67945 -0.305054)
			(end -0.12065 -0.305054)
			(stroke
				(width 0.1)
				(type default)
			)
			(layer "F.Fab")
		)
		(fp_line
			(start -0.12065 -0.305054)
			(end -0.12065 -0.2794)
			(stroke
				(width 0.1)
				(type default)
			)
			(layer "F.Fab")
		)
		(pad "1" smd circle
			(at -0.40005 0 270)
			(size 0 0)
			(layers "F.Cu" "F.Mask" "F.Paste")
			(net "P3V3_SSD8_CO_MODE")
		)
		(pad "2" smd circle
			(at 0.40005 0 270)
			(size 0 0)
			(layers "F.Cu" "F.Mask" "F.Paste")
			(net "GND")
		)
	)
	(footprint ""
		(layer "F.Cu")
		(at 380.711456 -286.844232 -90)
		(property "Reference" "R4594"
			(at 0 0 270)
			(layer "F.SilkS")
			(hide yes)
			(effects
				(font
					(size 1.27 1.27)
				)
			)
		)
		(property "Value" ""
			(at 0 0 270)
			(layer "F.Fab")
			(effects
				(font
					(size 1.27 1.27)
				)
			)
		)
		(duplicate_pad_numbers_are_jumpers no)
		(fp_line
			(start -0.7874 0.4064)
			(end -0.7874 -0.4064)
			(stroke
				(width 0.1524)
				(type default)
			)
			(layer "F.SilkS")
		)
		(fp_line
			(start 0.7874 0.4064)
			(end -0.7874 0.4064)
			(stroke
				(width 0.1524)
				(type default)
			)
			(layer "F.SilkS")
		)
		(fp_line
			(start -0.7874 -0.4064)
			(end 0.7874 -0.4064)
			(stroke
				(width 0.1524)
				(type default)
			)
			(layer "F.SilkS")
		)
		(fp_line
			(start 0.7874 -0.4064)
			(end 0.7874 0.4064)
			(stroke
				(width 0.1524)
				(type default)
			)
			(layer "F.SilkS")
		)
		(fp_line
			(start -0.67945 0.3048)
			(end -0.67945 -0.305054)
			(stroke
				(width 0.1)
				(type default)
			)
			(layer "F.Fab")
		)
		(fp_line
			(start -0.12065 0.3048)
			(end -0.67945 0.3048)
			(stroke
				(width 0.1)
				(type default)
			)
			(layer "F.Fab")
		)
		(fp_line
			(start 0.120396 0.3048)
			(end 0.120396 0.2794)
			(stroke
				(width 0.1)
				(type default)
			)
			(layer "F.Fab")
		)
		(fp_line
			(start 0.67945 0.3048)
			(end 0.120396 0.3048)
			(stroke
				(width 0.1)
				(type default)
			)
			(layer "F.Fab")
		)
		(fp_line
			(start -0.12065 0.2794)
			(end -0.12065 0.3048)
			(stroke
				(width 0.1)
				(type default)
			)
			(layer "F.Fab")
		)
		(fp_line
			(start 0.120396 0.2794)
			(end -0.12065 0.2794)
			(stroke
				(width 0.1)
				(type default)
			)
			(layer "F.Fab")
		)
		(fp_line
			(start -0.12065 -0.2794)
			(end 0.12065 -0.2794)
			(stroke
				(width 0.1)
				(type default)
			)
			(layer "F.Fab")
		)
		(fp_line
			(start 0.12065 -0.2794)
			(end 0.12065 -0.3048)
			(stroke
				(width 0.1)
				(type default)
			)
			(layer "F.Fab")
		)
		(fp_line
			(start 0.12065 -0.3048)
			(end 0.67945 -0.3048)
			(stroke
				(width 0.1)
				(type default)
			)
			(layer "F.Fab")
		)
		(fp_line
			(start 0.67945 -0.3048)
			(end 0.67945 0.3048)
			(stroke
				(width 0.1)
				(type default)
			)
			(layer "F.Fab")
		)
		(fp_line
			(start -0.67945 -0.305054)
			(end -0.12065 -0.305054)
			(stroke
				(width 0.1)
				(type default)
			)
			(layer "F.Fab")
		)
		(fp_line
			(start -0.12065 -0.305054)
			(end -0.12065 -0.2794)
			(stroke
				(width 0.1)
				(type default)
			)
			(layer "F.Fab")
		)
		(pad "1" smd circle
			(at -0.40005 0 270)
			(size 0 0)
			(layers "F.Cu" "F.Mask" "F.Paste")
			(net "PCEPLL6_VDDA18_PEX3")
		)
		(pad "2" smd circle
			(at 0.40005 0 270)
			(size 0 0)
			(layers "F.Cu" "F.Mask" "F.Paste")
			(net "PCEPLL6_VDDA18_PEX3_R")
		)
	)
	(footprint ""
		(layer "F.Cu")
		(at 210.054698 -235.76407 -90)
		(property "Reference" "R6319"
			(at 0 0 270)
			(layer "F.SilkS")
			(hide yes)
			(effects
				(font
					(size 1.27 1.27)
				)
			)
		)
		(property "Value" ""
			(at 0 0 270)
			(layer "F.Fab")
			(effects
				(font
					(size 1.27 1.27)
				)
			)
		)
		(duplicate_pad_numbers_are_jumpers no)
		(fp_line
			(start -0.7874 0.4064)
			(end -0.7874 -0.4064)
			(stroke
				(width 0.1524)
				(type default)
			)
			(layer "F.SilkS")
		)
		(fp_line
			(start 0.7874 0.4064)
			(end -0.7874 0.4064)
			(stroke
				(width 0.1524)
				(type default)
			)
			(layer "F.SilkS")
		)
		(fp_line
			(start -0.7874 -0.4064)
			(end 0.7874 -0.4064)
			(stroke
				(width 0.1524)
				(type default)
			)
			(layer "F.SilkS")
		)
		(fp_line
			(start 0.7874 -0.4064)
			(end 0.7874 0.4064)
			(stroke
				(width 0.1524)
				(type default)
			)
			(layer "F.SilkS")
		)
		(fp_line
			(start -0.67945 0.3048)
			(end -0.67945 -0.305054)
			(stroke
				(width 0.1)
				(type default)
			)
			(layer "F.Fab")
		)
		(fp_line
			(start -0.12065 0.3048)
			(end -0.67945 0.3048)
			(stroke
				(width 0.1)
				(type default)
			)
			(layer "F.Fab")
		)
		(fp_line
			(start 0.120396 0.3048)
			(end 0.120396 0.2794)
			(stroke
				(width 0.1)
				(type default)
			)
			(layer "F.Fab")
		)
		(fp_line
			(start 0.67945 0.3048)
			(end 0.120396 0.3048)
			(stroke
				(width 0.1)
				(type default)
			)
			(layer "F.Fab")
		)
		(fp_line
			(start -0.12065 0.2794)
			(end -0.12065 0.3048)
			(stroke
				(width 0.1)
				(type default)
			)
			(layer "F.Fab")
		)
		(fp_line
			(start 0.120396 0.2794)
			(end -0.12065 0.2794)
			(stroke
				(width 0.1)
				(type default)
			)
			(layer "F.Fab")
		)
		(fp_line
			(start -0.12065 -0.2794)
			(end 0.12065 -0.2794)
			(stroke
				(width 0.1)
				(type default)
			)
			(layer "F.Fab")
		)
		(fp_line
			(start 0.12065 -0.2794)
			(end 0.12065 -0.3048)
			(stroke
				(width 0.1)
				(type default)
			)
			(layer "F.Fab")
		)
		(fp_line
			(start 0.12065 -0.3048)
			(end 0.67945 -0.3048)
			(stroke
				(width 0.1)
				(type default)
			)
			(layer "F.Fab")
		)
		(fp_line
			(start 0.67945 -0.3048)
			(end 0.67945 0.3048)
			(stroke
				(width 0.1)
				(type default)
			)
			(layer "F.Fab")
		)
		(fp_line
			(start -0.67945 -0.305054)
			(end -0.12065 -0.305054)
			(stroke
				(width 0.1)
				(type default)
			)
			(layer "F.Fab")
		)
		(fp_line
			(start -0.12065 -0.305054)
			(end -0.12065 -0.2794)
			(stroke
				(width 0.1)
				(type default)
			)
			(layer "F.Fab")
		)
		(pad "1" smd circle
			(at -0.40005 0 270)
			(size 0 0)
			(layers "F.Cu" "F.Mask" "F.Paste")
			(net "SMB_PEX_LS_SCL")
		)
		(pad "2" smd circle
			(at 0.40005 0 270)
			(size 0 0)
			(layers "F.Cu" "F.Mask" "F.Paste")
			(net "SMB_PEX_MUX_SCL")
		)
	)
	(footprint ""
		(layer "F.Cu")
		(at 145.972276 -32.848042 90)
		(property "Reference" "PC922"
			(at 0 0 90)
			(layer "F.SilkS")
			(hide yes)
			(effects
				(font
					(size 1.27 1.27)
				)
			)
		)
		(property "Value" ""
			(at 0 0 90)
			(layer "F.Fab")
			(effects
				(font
					(size 1.27 1.27)
				)
			)
		)
		(duplicate_pad_numbers_are_jumpers no)
		(fp_line
			(start 0.7874 -0.4064)
			(end 0.7874 0.4064)
			(stroke
				(width 0.1524)
				(type default)
			)
			(layer "F.SilkS")
		)
		(fp_line
			(start -0.7874 -0.4064)
			(end 0.7874 -0.4064)
			(stroke
				(width 0.1524)
				(type default)
			)
			(layer "F.SilkS")
		)
		(fp_line
			(start 0.7874 0.4064)
			(end -0.7874 0.4064)
			(stroke
				(width 0.1524)
				(type default)
			)
			(layer "F.SilkS")
		)
		(fp_line
			(start -0.7874 0.4064)
			(end -0.7874 -0.4064)
			(stroke
				(width 0.1524)
				(type default)
			)
			(layer "F.SilkS")
		)
		(fp_line
			(start -0.12065 -0.305054)
			(end -0.12065 -0.2794)
			(stroke
				(width 0.1)
				(type default)
			)
			(layer "F.Fab")
		)
		(fp_line
			(start -0.67945 -0.305054)
			(end -0.12065 -0.305054)
			(stroke
				(width 0.1)
				(type default)
			)
			(layer "F.Fab")
		)
		(fp_line
			(start 0.67945 -0.3048)
			(end 0.67945 0.3048)
			(stroke
				(width 0.1)
				(type default)
			)
			(layer "F.Fab")
		)
		(fp_line
			(start 0.12065 -0.3048)
			(end 0.67945 -0.3048)
			(stroke
				(width 0.1)
				(type default)
			)
			(layer "F.Fab")
		)
		(fp_line
			(start 0.12065 -0.2794)
			(end 0.12065 -0.3048)
			(stroke
				(width 0.1)
				(type default)
			)
			(layer "F.Fab")
		)
		(fp_line
			(start -0.12065 -0.2794)
			(end 0.12065 -0.2794)
			(stroke
				(width 0.1)
				(type default)
			)
			(layer "F.Fab")
		)
		(fp_line
			(start 0.120396 0.2794)
			(end -0.12065 0.2794)
			(stroke
				(width 0.1)
				(type default)
			)
			(layer "F.Fab")
		)
		(fp_line
			(start -0.12065 0.2794)
			(end -0.12065 0.3048)
			(stroke
				(width 0.1)
				(type default)
			)
			(layer "F.Fab")
		)
		(fp_line
			(start 0.67945 0.3048)
			(end 0.120396 0.3048)
			(stroke
				(width 0.1)
				(type default)
			)
			(layer "F.Fab")
		)
		(fp_line
			(start 0.120396 0.3048)
			(end 0.120396 0.2794)
			(stroke
				(width 0.1)
				(type default)
			)
			(layer "F.Fab")
		)
		(fp_line
			(start -0.12065 0.3048)
			(end -0.67945 0.3048)
			(stroke
				(width 0.1)
				(type default)
			)
			(layer "F.Fab")
		)
		(fp_line
			(start -0.67945 0.3048)
			(end -0.67945 -0.305054)
			(stroke
				(width 0.1)
				(type default)
			)
			(layer "F.Fab")
		)
		(pad "1" smd circle
			(at -0.40005 0 90)
			(size 0 0)
			(layers "F.Cu" "F.Mask" "F.Paste")
			(net "P3V3_SSD5_CO_GATE")
		)
		(pad "2" smd circle
			(at 0.40005 0 90)
			(size 0 0)
			(layers "F.Cu" "F.Mask" "F.Paste")
			(net "GND")
		)
	)
	(footprint ""
		(layer "F.Cu")
		(at 376.34926 -284.195012 -90)
		(property "Reference" "C3560"
			(at 0 0 270)
			(layer "F.SilkS")
			(hide yes)
			(effects
				(font
					(size 1.27 1.27)
				)
			)
		)
		(property "Value" ""
			(at 0 0 270)
			(layer "F.Fab")
			(effects
				(font
					(size 1.27 1.27)
				)
			)
		)
		(duplicate_pad_numbers_are_jumpers no)
		(fp_line
			(start -0.299974 0.150114)
			(end -0.299974 -0.150114)
			(stroke
				(width 0.1)
				(type default)
			)
			(layer "F.Fab")
		)
		(fp_line
			(start 0.299974 0.150114)
			(end -0.299974 0.150114)
			(stroke
				(width 0.1)
				(type default)
			)
			(layer "F.Fab")
		)
		(fp_line
			(start -0.299974 -0.150114)
			(end 0.299974 -0.150114)
			(stroke
				(width 0.1)
				(type default)
			)
			(layer "F.Fab")
		)
		(fp_line
			(start 0.299974 -0.150114)
			(end 0.299974 0.150114)
			(stroke
				(width 0.1)
				(type default)
			)
			(layer "F.Fab")
		)
		(pad "1" smd rect
			(at -0.2667 0 270)
			(size 0.3048 0.381)
			(layers "F.Cu" "F.Mask" "F.Paste")
			(net "P1V8_PLL0_PEX3")
		)
		(pad "2" smd rect
			(at 0.2667 0 270)
			(size 0.3048 0.381)
			(layers "F.Cu" "F.Mask" "F.Paste")
			(net "GND")
		)
	)
)
